# BASEBOARD_FAB2 (Tioga Pass) — schematic netlist excerpt (pin names and nets, part order shuffled) for the footprints in the layout excerpt that follows; sources: Cadence DE-HDL packaged netlist, KiCad conversion of Wiwynn_Tioga_Pass_MB.brd

R7W10  RES  0.0 5% CHIP  pkg 0402  page 120 : A = FM_CPU0_RC_ERROR_N ; B = FM_CPU0_RC_ERROR_R1_N
R9E16  RES  33.2 1% CHIP  pkg 0402  page 139 : A = RMII_PCH_SPRNGVLLE_ARB_IN_R ; B = RMII_PCH_SPRNGVLLE_ARB_IN
C2G15  CAP_A  47UF 4V 20% X5R  pkg 0603V  page 225 : A = PVDDQ_GHJ ; B = GND

(kicad_pcb
	(version 20260206)
	(generator "pcbnew")
	(generator_version "10.0")
	(general
		(thickness 1.6)
		(legacy_teardrops no)
	)
	(paper "A4")
	(title_block
		(title "Wiwynn_Tioga_Pass_MB.brd")
		(comment 1 "Tioga Pass / footprints 984-986 of 4770")
	)
	(layers
		(0 "F.Cu" signal "TOP")
		(4 "In1.Cu" signal "L2GND")
		(6 "In2.Cu" signal "L3")
		(8 "In3.Cu" signal "L4GND")
		(10 "In4.Cu" signal "L5")
		(12 "In5.Cu" signal "L6GND")
		(14 "In6.Cu" signal "L7VCC")
		(16 "In7.Cu" signal "L8VCC")
		(18 "In8.Cu" signal "L9GND")
		(20 "In9.Cu" signal "L10")
		(22 "In10.Cu" signal "L11GND")
		(24 "In11.Cu" signal "L12")
		(26 "In12.Cu" signal "L13GND")
		(2 "B.Cu" signal "BOTTOM")
		(9 "F.Adhes" user "F.Adhesive")
		(11 "B.Adhes" user "B.Adhesive")
		(13 "F.Paste" user "Package Geometry/Pastemask Top")
		(15 "B.Paste" user "Package Geometry/Pastemask Bottom")
		(5 "F.SilkS" user "Ref Des/Silkscreen Top")
		(7 "B.SilkS" user "Ref Des/Silkscreen Bottom")
		(1 "F.Mask" user "Board Geometry/Soldermask Top")
		(3 "B.Mask" user "Board Geometry/Soldermask Bottom")
		(17 "Dwgs.User" user "User.Drawings")
		(19 "Cmts.User" user "User.Comments")
		(21 "Eco1.User" user "User.Eco1")
		(23 "Eco2.User" user "User.Eco2")
		(25 "Edge.Cuts" user "Board Geometry/Outline")
		(27 "Margin" user)
		(31 "F.CrtYd" user "Package Geometry/Place Bound Top")
		(29 "B.CrtYd" user "Package Geometry/Place Bound Bottom")
		(35 "F.Fab" user "Ref Des/Assembly Top")
		(33 "B.Fab" user "Ref Des/Assembly Bottom")
	)
	(footprint ""
		(layer "F.Cu")
		(at 413.3342 -114.2492 -90)
		(property "Reference" "R7W10"
			(at -0.8382 -0.67818 270)
			(unlocked yes)
			(layer "F.SilkS")
			(effects
				(font
					(size 0.4064 0.254)
					(thickness 0.1524)
				)
				(justify left)
			)
		)
		(property "Value" ""
			(at 0 0 270)
			(layer "F.Fab")
			(effects
				(font
					(size 1.27 1.27)
				)
			)
		)
		(duplicate_pad_numbers_are_jumpers no)
		(fp_poly
			(pts
				(xy -0.2794 -0.1016) (xy 0.2794 -0.1016) (xy 0.2794 0.9906) (xy -0.2794 0.9906)
			)
			(stroke
				(width 0)
				(type default)
			)
			(fill no)
			(layer "F.CrtYd")
		)
		(fp_line
			(start -0.2794 0.9906)
			(end 0.2794 0.9906)
			(stroke
				(width 0.1)
				(type default)
			)
			(layer "F.Fab")
		)
		(fp_line
			(start 0.2794 0.9906)
			(end 0.2794 -0.1016)
			(stroke
				(width 0.1)
				(type default)
			)
			(layer "F.Fab")
		)
		(fp_line
			(start -0.2794 -0.1016)
			(end -0.2794 0.9906)
			(stroke
				(width 0.1)
				(type default)
			)
			(layer "F.Fab")
		)
		(fp_line
			(start 0.2794 -0.1016)
			(end -0.2794 -0.1016)
			(stroke
				(width 0.1)
				(type default)
			)
			(layer "F.Fab")
		)
		(pad "1" smd rect
			(at 0 0 270)
			(size 0.508 0.508)
			(layers "F.Cu" "F.Mask" "F.Paste")
			(net "FM_CPU0_RC_ERROR_N")
		)
		(pad "2" smd rect
			(at 0 0.889 270)
			(size 0.508 0.508)
			(layers "F.Cu" "F.Mask" "F.Paste")
			(net "FM_CPU0_RC_ERROR_R1_N")
		)
		(zone
			(layer "F.Cu")
			(hatch none 0.5)
			(connect_pads
				(clearance 0)
			)
			(min_thickness 0.25)
			(keepout
				(tracks not_allowed)
				(vias allowed)
				(pads allowed)
				(copperpour not_allowed)
				(footprints allowed)
			)
			(placement
				(enabled no)
				(sheetname "")
			)
			(fill
				(thermal_gap 0.5)
				(thermal_bridge_width 0.5)
				(island_removal_mode 0)
			)
			(polygon
				(pts
					(xy 412.6992 -114.5032) (xy 412.6992 -113.9952) (xy 413.0802 -113.9952) (xy 413.0802 -114.5032)
				)
			)
		)
		(zone
			(layer "F.Cu")
			(hatch none 0.5)
			(connect_pads
				(clearance 0)
			)
			(min_thickness 0.25)
			(keepout
				(tracks allowed)
				(vias not_allowed)
				(pads allowed)
				(copperpour not_allowed)
				(footprints allowed)
			)
			(placement
				(enabled no)
				(sheetname "")
			)
			(fill
				(thermal_gap 0.5)
				(thermal_bridge_width 0.5)
				(island_removal_mode 0)
			)
			(polygon
				(pts
					(xy 413.0802 -114.5032) (xy 413.0802 -113.9952) (xy 412.6992 -113.9952) (xy 412.6992 -114.5032)
				)
			)
		)
	)
	(footprint ""
		(layer "F.Cu")
		(at 93.038168 -3.321812 -90)
		(property "Reference" "C2G15"
			(at 0 0 270)
			(layer "F.SilkS")
			(hide yes)
			(effects
				(font
					(size 1.27 1.27)
				)
			)
		)
		(property "Value" ""
			(at 0 0 270)
			(layer "F.Fab")
			(effects
				(font
					(size 1.27 1.27)
				)
			)
		)
		(duplicate_pad_numbers_are_jumpers no)
		(fp_rect
			(start -0.500126 1.598422)
			(end 0.500126 -0.201422)
			(stroke
				(width 0)
				(type default)
			)
			(fill no)
			(layer "F.CrtYd")
		)
		(fp_line
			(start -0.500126 1.598422)
			(end -0.500126 -0.201422)
			(stroke
				(width 0.1)
				(type default)
			)
			(layer "F.Fab")
		)
		(fp_line
			(start 0.500126 1.598422)
			(end -0.500126 1.598422)
			(stroke
				(width 0.1)
				(type default)
			)
			(layer "F.Fab")
		)
		(fp_line
			(start -0.500126 -0.201422)
			(end 0.500126 -0.201422)
			(stroke
				(width 0.1)
				(type default)
			)
			(layer "F.Fab")
		)
		(fp_line
			(start 0.500126 -0.201422)
			(end 0.500126 1.598422)
			(stroke
				(width 0.1)
				(type default)
			)
			(layer "F.Fab")
		)
		(pad "1" smd rect
			(at 0 0 180)
			(size 0.889 0.9906)
			(layers "F.Cu" "F.Mask" "F.Paste")
			(net "PVDDQ_GHJ")
		)
		(pad "2" smd rect
			(at 0 1.397 180)
			(size 0.889 0.9906)
			(layers "F.Cu" "F.Mask" "F.Paste")
			(net "GND")
		)
		(zone
			(layer "F.Cu")
			(hatch none 0.5)
			(connect_pads
				(clearance 0)
			)
			(min_thickness 0.25)
			(keepout
				(tracks not_allowed)
				(vias allowed)
				(pads allowed)
				(copperpour not_allowed)
				(footprints allowed)
			)
			(placement
				(enabled no)
				(sheetname "")
			)
			(fill
				(thermal_gap 0.5)
				(thermal_bridge_width 0.5)
				(island_removal_mode 0)
			)
			(polygon
				(pts
					(xy 92.085668 -3.817112) (xy 92.085668 -2.826512) (xy 92.593668 -2.826512) (xy 92.593668 -3.817112)
				)
			)
		)
		(zone
			(layer "F.Cu")
			(hatch none 0.5)
			(connect_pads
				(clearance 0)
			)
			(min_thickness 0.25)
			(keepout
				(tracks allowed)
				(vias not_allowed)
				(pads allowed)
				(copperpour not_allowed)
				(footprints allowed)
			)
			(placement
				(enabled no)
				(sheetname "")
			)
			(fill
				(thermal_gap 0.5)
				(thermal_bridge_width 0.5)
				(island_removal_mode 0)
			)
			(polygon
				(pts
					(xy 92.085668 -3.817112) (xy 92.085668 -2.826512) (xy 92.593668 -2.826512) (xy 92.593668 -3.817112)
				)
			)
		)
	)
	(footprint ""
		(layer "F.Cu")
		(at 478.1931 -42.9514 -90)
		(property "Reference" "R9E16"
			(at 0 0 270)
			(layer "F.SilkS")
			(hide yes)
			(effects
				(font
					(size 1.27 1.27)
				)
			)
		)
		(property "Value" ""
			(at 0 0 270)
			(layer "F.Fab")
			(effects
				(font
					(size 1.27 1.27)
				)
			)
		)
		(duplicate_pad_numbers_are_jumpers no)
		(fp_poly
			(pts
				(xy -0.2794 -0.1016) (xy 0.2794 -0.1016) (xy 0.2794 0.9906) (xy -0.2794 0.9906)
			)
			(stroke
				(width 0)
				(type default)
			)
			(fill no)
			(layer "F.CrtYd")
		)
		(fp_line
			(start -0.2794 0.9906)
			(end 0.2794 0.9906)
			(stroke
				(width 0.1)
				(type default)
			)
			(layer "F.Fab")
		)
		(fp_line
			(start 0.2794 0.9906)
			(end 0.2794 -0.1016)
			(stroke
				(width 0.1)
				(type default)
			)
			(layer "F.Fab")
		)
		(fp_line
			(start -0.2794 -0.1016)
			(end -0.2794 0.9906)
			(stroke
				(width 0.1)
				(type default)
			)
			(layer "F.Fab")
		)
		(fp_line
			(start 0.2794 -0.1016)
			(end -0.2794 -0.1016)
			(stroke
				(width 0.1)
				(type default)
			)
			(layer "F.Fab")
		)
		(pad "1" smd rect
			(at 0 0 270)
			(size 0.508 0.508)
			(layers "F.Cu" "F.Mask" "F.Paste")
			(net "RMII_PCH_SPRNGVLLE_ARB_IN_R")
		)
		(pad "2" smd rect
			(at 0 0.889 270)
			(size 0.508 0.508)
			(layers "F.Cu" "F.Mask" "F.Paste")
			(net "RMII_PCH_SPRNGVLLE_ARB_IN")
		)
		(zone
			(layer "F.Cu")
			(hatch none 0.5)
			(connect_pads
				(clearance 0)
			)
			(min_thickness 0.25)
			(keepout
				(tracks not_allowed)
				(vias allowed)
				(pads allowed)
				(copperpour not_allowed)
				(footprints allowed)
			)
			(placement
				(enabled no)
				(sheetname "")
			)
			(fill
				(thermal_gap 0.5)
				(thermal_bridge_width 0.5)
				(island_removal_mode 0)
			)
			(polygon
				(pts
					(xy 477.5581 -43.2054) (xy 477.5581 -42.6974) (xy 477.9391 -42.6974) (xy 477.9391 -43.2054)
				)
			)
		)
		(zone
			(layer "F.Cu")
			(hatch none 0.5)
			(connect_pads
				(clearance 0)
			)
			(min_thickness 0.25)
			(keepout
				(tracks allowed)
				(vias not_allowed)
				(pads allowed)
				(copperpour not_allowed)
				(footprints allowed)
			)
			(placement
				(enabled no)
				(sheetname "")
			)
			(fill
				(thermal_gap 0.5)
				(thermal_bridge_width 0.5)
				(island_removal_mode 0)
			)
			(polygon
				(pts
					(xy 477.9391 -43.2054) (xy 477.9391 -42.6974) (xy 477.5581 -42.6974) (xy 477.5581 -43.2054)
				)
			)
		)
	)
)
